FILE_TYPE = MACRO_DRAWING;
SET COLOR_WIRE YELLOW;
SET COLOR_PROP ORANGE;
SET COLOR_DOT WHITE;
SET COLOR_ARC YELLOW;
SET COLOR_BODY GREEN;
SET COLOR_NOTE PURPLE;
SET PROP_DISPLAY VALUE;
SET PAGE_NUMBER P59;
SET PATH_NUMBER P37;
FORCEADD ME_DUMMY_SYMBOL..1
(-3125 4675);
FORCEPROP 1 LAST MATERIAL EMPTY
J 0
(-3319 4807);
DISPLAY 0.723404 (-3319 4807);
PAINT GREEN (-3319 4807);
FORCEPROP 1 LAST PART_NUMBER DUMMY1
J 0
(-3319 4872);
DISPLAY 0.723404 (-3319 4872);
PAINT GREEN (-3319 4872);
FORCEPROP 2 LAST PART_TYPE MECH
J 0
(-3300 5025);
DISPLAY 0.680851 (-3300 5025);
FORCEPROP 2 LAST VALUE QUANTA_LOGO_7X26
J 0
(-3300 4975);
DISPLAY 0.680851 (-3300 4975);
FORCEPROP 1 LAST CDS_LMAN_SYM_OUTLINE -200,125,200,-125
J 0
(-3125 4675);
DISPLAY 0.468085 (-3125 4675);
PAINT GREEN (-3125 4675);
DISPLAY INVISIBLE (-3125 4675);
FORCEPROP 1 LAST NEEDS_NO_SIZE TRUE
J 0
(-2925 4607);
DISPLAY 0.723404 (-2925 4607);
PAINT GREEN (-2925 4607);
DISPLAY INVISIBLE (-2925 4607);
FORCEPROP 1 LAST PIN_TEXT_VISIBLE True
J 0
(-3125 4675);
DISPLAY 0.489362 (-3125 4675);
PAINT GREEN (-3125 4675);
DISPLAY INVISIBLE (-3125 4675);
FORCEPROP 1 LAST PIN_NAMES_ROTATE True
J 0
(-3125 4675);
DISPLAY 0.489362 (-3125 4675);
PAINT GREEN (-3125 4675);
DISPLAY INVISIBLE (-3125 4675);
FORCEPROP 1 LAST PATH I27
J 0
(-2925 4550);
DISPLAY 0.723404 (-2925 4550);
PAINT GREEN (-2925 4550);
DISPLAY INVISIBLE (-2925 4550);
FORCEPROP 2 LAST CDS_LIB pure_quanta
J 0
(-3125 4675);
DISPLAY INVISIBLE (-3125 4675);
FORCEPROP 1 LAST $LOCATION ME1
J 0
(-3319 4936);
DISPLAY 0.723404 (-3319 4936);
PAINT GREEN (-3319 4936);
FORCEPROP 0 LAST CDS_LOCATION ME1
J 0
(-3300 5075);
DISPLAY 0.680851 (-3300 5075);
DISPLAY INVISIBLE (-3300 5075);
FORCEADD ME_DUMMY_SYMBOL..1
(-1875 4650);
FORCEPROP 2 LAST VALUE WEEE
J 0
(-2050 4950);
DISPLAY 0.680851 (-2050 4950);
FORCEPROP 1 LAST PART_NUMBER DUMMY2
J 0
(-2069 4847);
DISPLAY 0.723404 (-2069 4847);
PAINT GREEN (-2069 4847);
FORCEPROP 1 LAST MATERIAL EMPTY
J 0
(-2069 4782);
DISPLAY 0.723404 (-2069 4782);
PAINT GREEN (-2069 4782);
FORCEPROP 2 LAST PART_TYPE MECH
J 0
(-2050 5000);
DISPLAY 0.680851 (-2050 5000);
FORCEPROP 1 LAST CDS_LMAN_SYM_OUTLINE -200,125,200,-125
J 0
(-1875 4650);
DISPLAY 0.468085 (-1875 4650);
PAINT GREEN (-1875 4650);
DISPLAY INVISIBLE (-1875 4650);
FORCEPROP 1 LAST NEEDS_NO_SIZE TRUE
J 0
(-1675 4582);
DISPLAY 0.723404 (-1675 4582);
PAINT GREEN (-1675 4582);
DISPLAY INVISIBLE (-1675 4582);
FORCEPROP 1 LAST PIN_TEXT_VISIBLE True
J 0
(-1875 4650);
DISPLAY 0.489362 (-1875 4650);
PAINT GREEN (-1875 4650);
DISPLAY INVISIBLE (-1875 4650);
FORCEPROP 1 LAST PIN_NAMES_ROTATE True
J 0
(-1875 4650);
DISPLAY 0.489362 (-1875 4650);
PAINT GREEN (-1875 4650);
DISPLAY INVISIBLE (-1875 4650);
FORCEPROP 1 LAST PATH I28
J 0
(-1675 4525);
DISPLAY 0.723404 (-1675 4525);
PAINT GREEN (-1675 4525);
DISPLAY INVISIBLE (-1675 4525);
FORCEPROP 2 LAST CDS_LIB pure_quanta
J 0
(-1875 4650);
DISPLAY INVISIBLE (-1875 4650);
FORCEPROP 1 LAST $LOCATION ME2
J 0
(-2069 4911);
DISPLAY 0.723404 (-2069 4911);
PAINT GREEN (-2069 4911);
FORCEPROP 0 LAST CDS_LOCATION ME2
J 0
(-2050 5050);
DISPLAY 0.680851 (-2050 5050);
DISPLAY INVISIBLE (-2050 5050);
FORCEADD ME_DUMMY_SYMBOL..1
(-350 4600);
FORCEPROP 2 LAST VALUE PB-E1_SMALL
J 0
(-525 4900);
DISPLAY 0.680851 (-525 4900);
FORCEPROP 2 LAST PART_TYPE MECH
J 0
(-525 4950);
DISPLAY 0.680851 (-525 4950);
FORCEPROP 1 LAST PART_NUMBER DUMMY3
J 0
(-544 4797);
DISPLAY 0.723404 (-544 4797);
PAINT GREEN (-544 4797);
FORCEPROP 1 LAST MATERIAL EMPTY
J 0
(-544 4732);
DISPLAY 0.723404 (-544 4732);
PAINT GREEN (-544 4732);
FORCEPROP 1 LAST CDS_LMAN_SYM_OUTLINE -200,125,200,-125
J 0
(-350 4600);
DISPLAY 0.468085 (-350 4600);
PAINT GREEN (-350 4600);
DISPLAY INVISIBLE (-350 4600);
FORCEPROP 1 LAST NEEDS_NO_SIZE TRUE
J 0
(-150 4532);
DISPLAY 0.723404 (-150 4532);
PAINT GREEN (-150 4532);
DISPLAY INVISIBLE (-150 4532);
FORCEPROP 1 LAST PIN_TEXT_VISIBLE True
J 0
(-350 4600);
DISPLAY 0.489362 (-350 4600);
PAINT GREEN (-350 4600);
DISPLAY INVISIBLE (-350 4600);
FORCEPROP 1 LAST PIN_NAMES_ROTATE True
J 0
(-350 4600);
DISPLAY 0.489362 (-350 4600);
PAINT GREEN (-350 4600);
DISPLAY INVISIBLE (-350 4600);
FORCEPROP 1 LAST PATH I29
J 0
(-150 4475);
DISPLAY 0.723404 (-150 4475);
PAINT GREEN (-150 4475);
DISPLAY INVISIBLE (-150 4475);
FORCEPROP 2 LAST CDS_LIB pure_quanta
J 0
(-350 4600);
DISPLAY INVISIBLE (-350 4600);
FORCEPROP 1 LAST LOCATION DM7
J 0
(-544 4861);
DISPLAY 0.723404 (-544 4861);
PAINT GREEN (-544 4861);
FORCEADD ME_DUMMY_SYMBOL..1
(5150 1975);
FORCEPROP 2 LAST PART_TYPE MECH
J 0
(4975 2325);
DISPLAY 0.680851 (4975 2325);
FORCEPROP 1 LAST PART_NUMBER DUMMY69
J 0
(4956 2172);
DISPLAY 0.723404 (4956 2172);
PAINT GREEN (4956 2172);
FORCEPROP 1 LAST MATERIAL EMPTY
J 0
(4956 2107);
DISPLAY 0.723404 (4956 2107);
PAINT GREEN (4956 2107);
FORCEPROP 2 LAST VALUE SNLABEL_7X7
J 0
(4975 2275);
DISPLAY 0.680851 (4975 2275);
FORCEPROP 1 LAST PIN_NAMES_ROTATE True
J 0
(5150 1975);
DISPLAY 0.489362 (5150 1975);
PAINT GREEN (5150 1975);
DISPLAY INVISIBLE (5150 1975);
FORCEPROP 1 LAST PIN_TEXT_VISIBLE True
J 0
(5150 1975);
DISPLAY 0.489362 (5150 1975);
PAINT GREEN (5150 1975);
DISPLAY INVISIBLE (5150 1975);
FORCEPROP 1 LAST NEEDS_NO_SIZE TRUE
J 0
(5350 1907);
DISPLAY 0.723404 (5350 1907);
PAINT GREEN (5350 1907);
DISPLAY INVISIBLE (5350 1907);
FORCEPROP 1 LAST CDS_LMAN_SYM_OUTLINE -200,125,200,-125
J 0
(5150 1975);
DISPLAY 0.468085 (5150 1975);
PAINT GREEN (5150 1975);
DISPLAY INVISIBLE (5150 1975);
FORCEPROP 1 LAST PATH I34
J 0
(5350 1850);
DISPLAY 0.723404 (5350 1850);
PAINT GREEN (5350 1850);
DISPLAY INVISIBLE (5350 1850);
FORCEPROP 2 LAST CDS_LIB pure_quanta
J 0
(5150 1975);
DISPLAY INVISIBLE (5150 1975);
FORCEPROP 1 LAST $LOCATION ME4
J 0
(4956 2236);
DISPLAY 0.723404 (4956 2236);
PAINT GREEN (4956 2236);
FORCEPROP 0 LAST CDS_LOCATION ME4
J 0
(4975 2375);
DISPLAY 0.680851 (4975 2375);
DISPLAY INVISIBLE (4975 2375);
FORCEADD DUMMY_SYMBOL..1
(-1600 3325);
FORCEPROP 1 LAST MATERIAL MECH
J 0
(-1796 3416);
DISPLAY 0.723404 (-1796 3416);
PAINT GREEN (-1796 3416);
FORCEPROP 2 LAST PART_TYPE MECH
J 0
(-1775 3700);
DISPLAY 0.680851 (-1775 3700);
FORCEPROP 1 LAST PART_NUMBER DUMMY9
J 0
(-1796 3502);
DISPLAY 0.723404 (-1796 3502);
PAINT GREEN (-1796 3502);
FORCEPROP 2 LAST VALUE BIOS_FLASH
J 0
(-1775 3650);
DISPLAY 0.680851 (-1775 3650);
FORCEPROP 2 LAST CDS_LIB pure_quanta
J 0
(-1600 3325);
DISPLAY INVISIBLE (-1600 3325);
FORCEPROP 1 LAST PATH I35
J 0
(-1400 3250);
DISPLAY 0.723404 (-1400 3250);
DISPLAY INVISIBLE (-1400 3250);
FORCEPROP 1 LAST CDS_LMAN_SYM_OUTLINE -200,75,200,-75
J 0
(-1600 3325);
DISPLAY 0.468085 (-1600 3325);
PAINT GREEN (-1600 3325);
DISPLAY INVISIBLE (-1600 3325);
FORCEPROP 1 LAST PIN_NAMES_ROTATE True
J 0
(-1600 3325);
DISPLAY 0.489362 (-1600 3325);
PAINT GREEN (-1600 3325);
DISPLAY INVISIBLE (-1600 3325);
FORCEPROP 1 LAST $LOCATION DM3
J 0
(-1796 3595);
DISPLAY 0.723404 (-1796 3595);
PAINT GREEN (-1796 3595);
FORCEPROP 0 LASTPIN (-1400 3350) $PN 1
R 1
J 0
(-1410 3360);
DISPLAY 0.680851 (-1410 3360);
PAINT MONO (-1410 3360);
FORCEPROP 0 LAST CDS_LOCATION DM3
J 0
(-1775 3750);
DISPLAY 0.680851 (-1775 3750);
DISPLAY INVISIBLE (-1775 3750);
FORCEPROP 0 LAST $SEC 1
J 0
(-1775 3750);
DISPLAY 0.680851 (-1775 3750);
PAINT MONO (-1775 3750);
DISPLAY INVISIBLE (-1775 3750);
FORCEPROP 0 LAST CDS_SEC 1
J 0
(-1775 3750);
DISPLAY 0.680851 (-1775 3750);
DISPLAY INVISIBLE (-1775 3750);
FORCEADD DUMMY_SYMBOL..1
(-3200 3250);
FORCEPROP 1 LAST PART_NUMBER DUMMY8
J 0
(-3396 3427);
DISPLAY 0.723404 (-3396 3427);
PAINT GREEN (-3396 3427);
FORCEPROP 2 LAST VALUE BMC_FLASH
J 0
(-3375 3575);
DISPLAY 0.680851 (-3375 3575);
FORCEPROP 2 LAST PART_TYPE MECH
J 0
(-3375 3625);
DISPLAY 0.680851 (-3375 3625);
FORCEPROP 1 LAST MATERIAL EMPTY
J 0
(-3396 3341);
DISPLAY 0.723404 (-3396 3341);
PAINT RED (-3396 3341);
FORCEPROP 1 LAST CDS_LMAN_SYM_OUTLINE -200,75,200,-75
J 0
(-3200 3250);
DISPLAY 0.468085 (-3200 3250);
PAINT GREEN (-3200 3250);
DISPLAY INVISIBLE (-3200 3250);
FORCEPROP 1 LAST PIN_NAMES_ROTATE True
J 0
(-3200 3250);
DISPLAY 0.489362 (-3200 3250);
PAINT GREEN (-3200 3250);
DISPLAY INVISIBLE (-3200 3250);
FORCEPROP 1 LAST PATH I36
J 0
(-3000 3175);
DISPLAY 0.723404 (-3000 3175);
DISPLAY INVISIBLE (-3000 3175);
FORCEPROP 2 LAST CDS_LIB pure_quanta
J 0
(-3200 3250);
DISPLAY INVISIBLE (-3200 3250);
FORCEPROP 1 LAST $LOCATION DM1
J 0
(-3396 3520);
DISPLAY 0.723404 (-3396 3520);
PAINT GREEN (-3396 3520);
FORCEPROP 0 LASTPIN (-3000 3275) $PN 1
R 1
J 0
(-3010 3285);
DISPLAY 0.680851 (-3010 3285);
PAINT MONO (-3010 3285);
FORCEPROP 0 LAST CDS_LOCATION DM1
J 0
(-3375 3675);
DISPLAY 0.680851 (-3375 3675);
DISPLAY INVISIBLE (-3375 3675);
FORCEPROP 0 LAST $SEC 1
J 0
(-3375 3675);
DISPLAY 0.680851 (-3375 3675);
PAINT MONO (-3375 3675);
DISPLAY INVISIBLE (-3375 3675);
FORCEPROP 0 LAST CDS_SEC 1
J 0
(-3375 3675);
DISPLAY 0.680851 (-3375 3675);
DISPLAY INVISIBLE (-3375 3675);
FORCEADD DUMMY_SYMBOL..1
(-2675 3250);
FORCEPROP 2 LAST PART_TYPE MECH
J 0
(-2850 3625);
DISPLAY 0.680851 (-2850 3625);
FORCEPROP 1 LAST PART_NUMBER DUMMY8
J 0
(-2871 3427);
DISPLAY 0.723404 (-2871 3427);
PAINT GREEN (-2871 3427);
FORCEPROP 1 LAST MATERIAL EMPTY
J 0
(-2871 3341);
DISPLAY 0.723404 (-2871 3341);
PAINT RED (-2871 3341);
FORCEPROP 2 LAST VALUE BMC_FLASH
J 0
(-2850 3575);
DISPLAY 0.680851 (-2850 3575);
FORCEPROP 2 LAST CDS_LIB pure_quanta
J 0
(-2675 3250);
DISPLAY INVISIBLE (-2675 3250);
FORCEPROP 1 LAST PATH I37
J 0
(-2475 3175);
DISPLAY 0.723404 (-2475 3175);
DISPLAY INVISIBLE (-2475 3175);
FORCEPROP 1 LAST PIN_NAMES_ROTATE True
J 0
(-2675 3250);
DISPLAY 0.489362 (-2675 3250);
PAINT GREEN (-2675 3250);
DISPLAY INVISIBLE (-2675 3250);
FORCEPROP 1 LAST CDS_LMAN_SYM_OUTLINE -200,75,200,-75
J 0
(-2675 3250);
DISPLAY 0.468085 (-2675 3250);
PAINT GREEN (-2675 3250);
DISPLAY INVISIBLE (-2675 3250);
FORCEPROP 1 LAST $LOCATION DM2
J 0
(-2871 3520);
DISPLAY 0.723404 (-2871 3520);
PAINT GREEN (-2871 3520);
FORCEPROP 0 LASTPIN (-2475 3275) $PN 1
R 1
J 0
(-2485 3285);
DISPLAY 0.680851 (-2485 3285);
PAINT MONO (-2485 3285);
FORCEPROP 0 LAST CDS_LOCATION DM2
J 0
(-2850 3675);
DISPLAY 0.680851 (-2850 3675);
DISPLAY INVISIBLE (-2850 3675);
FORCEPROP 0 LAST $SEC 1
J 0
(-2850 3675);
DISPLAY 0.680851 (-2850 3675);
PAINT MONO (-2850 3675);
DISPLAY INVISIBLE (-2850 3675);
FORCEPROP 0 LAST CDS_SEC 1
J 0
(-2850 3675);
DISPLAY 0.680851 (-2850 3675);
DISPLAY INVISIBLE (-2850 3675);
FORCEADD QUANTA_TITLE_BLOCK_C..3
(5875 -1275);
FORCEPROP 0 LAST CDS_CON_LAST_MODIFIED Fri Aug 25 17:25:50 2023
J 0
(3990 -1260);
PAINT MONO (3990 -1260);
DISPLAY INVISIBLE (3990 -1260);
FORCEPROP 2 LAST Q_DEPT 
J 1
(2112 -1226);
DISPLAY 1.957447 (2112 -1226);
PAINT GREEN (2112 -1226);
FORCEPROP 1 LAST CUSTOM_TXT_CDS <CON_LAST_MODIFIED>
J 0
(3990 -1260);
DISPLAY 0.978723 (3990 -1260);
FORCEPROP 2 LAST CUSTOM_TXT_CDS <XR_PAGE_TITLE>
J 0
(-2015 3975);
DISPLAY 0.638298 (-2015 3975);
PAINT PINK (-2015 3975);
DISPLAY INVISIBLE (-2015 3975);
FORCEPROP 1 LAST CUSTOM_TXT_CDS <NAME_2>
J 0
(2700 -1225);
FORCEPROP 1 LAST CUSTOM_TXT_CDS <NAME_1>
J 0
(2700 -1100);
FORCEPROP 1 LAST CUSTOM_TXT_CDS <Q_NUMBER>
J 0
(4472 -1172);
DISPLAY 1.212766 (4472 -1172);
FORCEPROP 1 LAST CUSTOM_TXT_CDS <Q_PROJ>
J 0
(3493 -1173);
DISPLAY 1.212766 (3493 -1173);
FORCEPROP 1 LAST CUSTOM_TXT_CDS <Q_REV>
J 0
(5691 -1172);
DISPLAY 1.212766 (5691 -1172);
FORCEPROP 1 LAST CUSTOM_TXT_CDS <CON_PAGE_NUM> OF <CON_TOTAL_PAGES>
J 0
(5429 -1257);
DISPLAY 0.978723 (5429 -1257);
FORCEPROP 1 LAST Q_TITLE DUMMY SYMBOL
J 0
(-3491 -1249);
DISPLAY 2.446809 (-3491 -1249);
PAINT GREEN (-3491 -1249);
FORCEPROP 2 LAST CDS_LIB pure_quanta
J 0
(5875 -1275);
PAINT MONO (5875 -1275);
DISPLAY INVISIBLE (5875 -1275);
FORCEPROP 1 LAST CDS_LMAN_SYM_OUTLINE -9475,6775,100,-125
J 0
(5875 -1275);
DISPLAY 0.468085 (5875 -1275);
PAINT GREEN (5875 -1275);
DISPLAY INVISIBLE (5875 -1275);
FORCEPROP 2 LAST PAGE_BORDER TRUE
J 0
(-2015 3975);
DISPLAY 0.638298 (-2015 3975);
PAINT PINK (-2015 3975);
DISPLAY INVISIBLE (-2015 3975);
FORCEPROP 1 LAST COMMENT_BODY TRUE
J 0
(5887 -1288);
DISPLAY 0.978723 (5887 -1288);
PAINT PEACH (5887 -1288);
DISPLAY INVISIBLE (5887 -1288);
FORCEPROP 2 LAST CDS_XR_PAGE_TITLE CR-59 : @SCM_LIB.SCM(SCH_1):PAGE59
J 0
(-2015 3975);
DISPLAY 0.638298 (-2015 3975);
PAINT PINK (-2015 3975);
DISPLAY INVISIBLE (-2015 3975);
FORCEADD DNS..1
(-3200 3225);
PAINT RED (-3200 3225);
FORCEPROP 1 LAST COMMENT_BODY TRUE
R 1
J 0
(-3125 3000);
DISPLAY 0.872340 (-3125 3000);
PAINT PEACH (-3125 3000);
DISPLAY INVISIBLE (-3125 3000);
FORCEPROP 2 LAST CDS_LIB mstr_misc
J 0
(-3200 3225);
DISPLAY INVISIBLE (-3200 3225);
FORCEADD DNS..1
(-2700 3225);
PAINT RED (-2700 3225);
FORCEPROP 2 LAST CDS_LIB mstr_misc
J 0
(-2700 3225);
DISPLAY INVISIBLE (-2700 3225);
FORCEPROP 1 LAST COMMENT_BODY TRUE
R 1
J 0
(-2625 3000);
DISPLAY 0.872340 (-2625 3000);
PAINT PEACH (-2625 3000);
DISPLAY INVISIBLE (-2625 3000);
FORCEADD DNS..1
(-3125 4650);
PAINT RED (-3125 4650);
FORCEPROP 2 LAST CDS_LIB mstr_misc
J 0
(-3125 4650);
DISPLAY INVISIBLE (-3125 4650);
FORCEPROP 1 LAST COMMENT_BODY TRUE
R 1
J 0
(-3050 4425);
DISPLAY 0.872340 (-3050 4425);
PAINT PEACH (-3050 4425);
DISPLAY INVISIBLE (-3050 4425);
FORCEADD DNS..1
(-1850 4650);
PAINT RED (-1850 4650);
FORCEPROP 1 LAST COMMENT_BODY TRUE
R 1
J 0
(-1775 4425);
DISPLAY 0.872340 (-1775 4425);
PAINT PEACH (-1775 4425);
DISPLAY INVISIBLE (-1775 4425);
FORCEPROP 2 LAST CDS_LIB mstr_misc
J 0
(-1850 4650);
DISPLAY INVISIBLE (-1850 4650);
FORCEADD DNS..1
(-375 4550);
PAINT RED (-375 4550);
FORCEPROP 1 LAST COMMENT_BODY TRUE
R 1
J 0
(-300 4325);
DISPLAY 0.872340 (-300 4325);
PAINT PEACH (-300 4325);
DISPLAY INVISIBLE (-300 4325);
FORCEPROP 2 LAST CDS_LIB mstr_misc
J 0
(-375 4550);
DISPLAY INVISIBLE (-375 4550);
FORCENOTE
HCS2F014010
(650 2400) 0;
DISPLAY LEFT (650 2400);
DISPLAY 1.021277 (650 2400);
PAINT WHITE (650 2400);
FORCENOTE
HCF0E015010
(3550 5150) 0;
DISPLAY LEFT (3550 5150);
DISPLAY 1.021277 (3550 5150);
PAINT WHITE (3550 5150);
FORCENOTE
HCLU2002010
(-750 2400) 0;
DISPLAY LEFT (-750 2400);
DISPLAY 1.021277 (-750 2400);
PAINT WHITE (-750 2400);
FORCENOTE
HCF0E016010
(900 5150) 0;
DISPLAY LEFT (900 5150);
DISPLAY 1.021277 (900 5150);
PAINT WHITE (900 5150);
FORCENOTE
BMC AMI LABEL
(625 2575) 0;
DISPLAY LEFT (625 2575);
DISPLAY 1.595745 (625 2575);
PAINT WHITE (625 2575);
FORCENOTE
EFI BIOS LABEL
(-750 2575) 0;
DISPLAY LEFT (-750 2575);
DISPLAY 1.595745 (-750 2575);
PAINT WHITE (-750 2575);
FORCENOTE
HCF0A001010
(2150 2400) 0;
DISPLAY LEFT (2150 2400);
DISPLAY 1.021277 (2150 2400);
PAINT WHITE (2150 2400);
FORCENOTE
SN+VPN+FB PN LABEL
(4525 2575) 0;
DISPLAY LEFT (4525 2575);
DISPLAY 1.595745 (4525 2575);
PAINT WHITE (4525 2575);
FORCENOTE
MAC LABEL
(2075 2575) 0;
DISPLAY LEFT (2075 2575);
DISPLAY 1.595745 (2075 2575);
PAINT WHITE (2075 2575);
FORCENOTE
SN LABEL
(3525 2575) 0;
DISPLAY LEFT (3525 2575);
DISPLAY 1.595745 (3525 2575);
PAINT WHITE (3525 2575);
QUIT
